(kicad_pcb
	(version 20260206)
	(generator "pcbnew")
	(generator_version "10.0")
	(general
		(thickness 1.6)
		(legacy_teardrops no)
	)
	(paper "A4")
	(title_block
		(title "03242023_DA0F0TMBIJ0_F0T_Motherboard_J_brd_V01_OCP.brd")
		(comment 1 "Grand Teton / footprints 3703-3706 of 6105")
	)
	(layers
		(0 "F.Cu" signal "TOP")
		(4 "In1.Cu" signal "GND")
		(6 "In2.Cu" signal "IN1")
		(8 "In3.Cu" signal "GND1")
		(10 "In4.Cu" signal "IN2")
		(12 "In5.Cu" signal "GND2")
		(14 "In6.Cu" signal "IN3")
		(16 "In7.Cu" signal "GND3")
		(18 "In8.Cu" signal "VCC")
		(20 "In9.Cu" signal "VCC1")
		(22 "In10.Cu" signal "GND4")
		(24 "In11.Cu" signal "IN4")
		(26 "In12.Cu" signal "GND5")
		(28 "In13.Cu" signal "IN5")
		(30 "In14.Cu" signal "GND6")
		(32 "In15.Cu" signal "IN6")
		(34 "In16.Cu" signal "GND7")
		(2 "B.Cu" signal "BOTTOM")
		(9 "F.Adhes" user "F.Adhesive")
		(11 "B.Adhes" user "B.Adhesive")
		(13 "F.Paste" user "Package Geometry/Pastemask Top")
		(15 "B.Paste" user "Package Geometry/Pastemask Bottom")
		(5 "F.SilkS" user "Ref Des/Silkscreen Top")
		(7 "B.SilkS" user "Ref Des/Silkscreen Bottom")
		(1 "F.Mask" user "Board Geometry/Soldermask Top")
		(3 "B.Mask" user "Board Geometry/Soldermask Bottom")
		(17 "Dwgs.User" user "User.Drawings")
		(19 "Cmts.User" user "User.Comments")
		(21 "Eco1.User" user "User.Eco1")
		(23 "Eco2.User" user "User.Eco2")
		(25 "Edge.Cuts" user "Board Geometry/Outline")
		(27 "Margin" user)
		(31 "F.CrtYd" user "Package Geometry/Place Bound Top")
		(29 "B.CrtYd" user "Package Geometry/Place Bound Bottom")
		(35 "F.Fab" user "Ref Des/Assembly Top")
		(33 "B.Fab" user "Ref Des/Assembly Bottom")
	)
	(footprint ""
		(layer "F.Cu")
		(at 96.983296 -70.78599)
		(property "Reference" "D86"
			(at -48.854106 50.178462 90)
			(unlocked yes)
			(layer "F.SilkS")
			(effects
				(font
					(size 0.635 0.4064)
					(thickness 0.1524)
				)
				(justify left)
			)
		)
		(property "Value" ""
			(at 0 0 0)
			(layer "F.Fab")
			(effects
				(font
					(size 1.27 1.27)
				)
			)
		)
		(duplicate_pad_numbers_are_jumpers no)
		(fp_line
			(start -0.90678 0.4826)
			(end -0.90678 -0.4699)
			(stroke
				(width 0.1524)
				(type default)
			)
			(layer "F.SilkS")
		)
		(fp_line
			(start -0.89408 -0.4826)
			(end 0.90678 -0.4826)
			(stroke
				(width 0.1524)
				(type default)
			)
			(layer "F.SilkS")
		)
		(fp_line
			(start -0.79248 -0.4826)
			(end 1.03378 -0.4826)
			(stroke
				(width 0.1524)
				(type default)
			)
			(layer "F.SilkS")
		)
		(fp_line
			(start -0.64008 -0.4826)
			(end 1.16078 -0.4826)
			(stroke
				(width 0.1524)
				(type default)
			)
			(layer "F.SilkS")
		)
		(fp_line
			(start 0.90678 -0.4826)
			(end 0.90678 0.4826)
			(stroke
				(width 0.1524)
				(type default)
			)
			(layer "F.SilkS")
		)
		(fp_line
			(start 0.90678 0.4826)
			(end -0.90678 0.4826)
			(stroke
				(width 0.1524)
				(type default)
			)
			(layer "F.SilkS")
		)
		(fp_line
			(start 1.03378 -0.4826)
			(end 1.03378 0.4826)
			(stroke
				(width 0.1524)
				(type default)
			)
			(layer "F.SilkS")
		)
		(fp_line
			(start 1.03378 0.4826)
			(end -0.79248 0.4826)
			(stroke
				(width 0.1524)
				(type default)
			)
			(layer "F.SilkS")
		)
		(fp_line
			(start 1.16078 -0.4826)
			(end 1.16078 0.4826)
			(stroke
				(width 0.1524)
				(type default)
			)
			(layer "F.SilkS")
		)
		(fp_line
			(start 1.16078 0.4826)
			(end -0.64008 0.4826)
			(stroke
				(width 0.1524)
				(type default)
			)
			(layer "F.SilkS")
		)
		(fp_line
			(start -0.499872 -0.249936)
			(end 0.499872 -0.249936)
			(stroke
				(width 0.1)
				(type default)
			)
			(layer "F.Fab")
		)
		(fp_line
			(start -0.499872 0.249936)
			(end -0.499872 -0.249936)
			(stroke
				(width 0.1)
				(type default)
			)
			(layer "F.Fab")
		)
		(fp_line
			(start 0.499872 -0.249936)
			(end 0.499872 0.249936)
			(stroke
				(width 0.1)
				(type default)
			)
			(layer "F.Fab")
		)
		(fp_line
			(start 0.499872 0.249936)
			(end -0.499872 0.249936)
			(stroke
				(width 0.1)
				(type default)
			)
			(layer "F.Fab")
		)
		(pad "A" smd rect
			(at -0.47498 0)
			(size 0.6096 0.7112)
			(layers "F.Cu" "F.Mask" "F.Paste")
			(net "LED_PWRGD_PVCCIN_CPU1")
		)
		(pad "C" smd rect
			(at 0.47498 0)
			(size 0.6096 0.7112)
			(layers "F.Cu" "F.Mask" "F.Paste")
			(net "LED_PWRGD_PVCCIN_CPU1_D")
		)
	)
	(footprint ""
		(layer "F.Cu")
		(at 83.4898 -35.651948 90)
		(property "Reference" "R4615"
			(at 0 0 90)
			(layer "F.SilkS")
			(hide yes)
			(effects
				(font
					(size 1.27 1.27)
				)
			)
		)
		(property "Value" ""
			(at 0 0 90)
			(layer "F.Fab")
			(effects
				(font
					(size 1.27 1.27)
				)
			)
		)
		(duplicate_pad_numbers_are_jumpers no)
		(fp_line
			(start 0.7874 -0.4064)
			(end 0.7874 0.4064)
			(stroke
				(width 0.1524)
				(type default)
			)
			(layer "F.SilkS")
		)
		(fp_line
			(start -0.7874 -0.4064)
			(end 0.7874 -0.4064)
			(stroke
				(width 0.1524)
				(type default)
			)
			(layer "F.SilkS")
		)
		(fp_line
			(start 0.7874 0.4064)
			(end -0.7874 0.4064)
			(stroke
				(width 0.1524)
				(type default)
			)
			(layer "F.SilkS")
		)
		(fp_line
			(start -0.7874 0.4064)
			(end -0.7874 -0.4064)
			(stroke
				(width 0.1524)
				(type default)
			)
			(layer "F.SilkS")
		)
		(fp_line
			(start -0.12065 -0.305054)
			(end -0.12065 -0.2794)
			(stroke
				(width 0.1)
				(type default)
			)
			(layer "F.Fab")
		)
		(fp_line
			(start -0.67945 -0.305054)
			(end -0.12065 -0.305054)
			(stroke
				(width 0.1)
				(type default)
			)
			(layer "F.Fab")
		)
		(fp_line
			(start 0.67945 -0.3048)
			(end 0.67945 0.3048)
			(stroke
				(width 0.1)
				(type default)
			)
			(layer "F.Fab")
		)
		(fp_line
			(start 0.12065 -0.3048)
			(end 0.67945 -0.3048)
			(stroke
				(width 0.1)
				(type default)
			)
			(layer "F.Fab")
		)
		(fp_line
			(start 0.12065 -0.2794)
			(end 0.12065 -0.3048)
			(stroke
				(width 0.1)
				(type default)
			)
			(layer "F.Fab")
		)
		(fp_line
			(start -0.12065 -0.2794)
			(end 0.12065 -0.2794)
			(stroke
				(width 0.1)
				(type default)
			)
			(layer "F.Fab")
		)
		(fp_line
			(start 0.120396 0.2794)
			(end -0.12065 0.2794)
			(stroke
				(width 0.1)
				(type default)
			)
			(layer "F.Fab")
		)
		(fp_line
			(start -0.12065 0.2794)
			(end -0.12065 0.3048)
			(stroke
				(width 0.1)
				(type default)
			)
			(layer "F.Fab")
		)
		(fp_line
			(start 0.67945 0.3048)
			(end 0.120396 0.3048)
			(stroke
				(width 0.1)
				(type default)
			)
			(layer "F.Fab")
		)
		(fp_line
			(start 0.120396 0.3048)
			(end 0.120396 0.2794)
			(stroke
				(width 0.1)
				(type default)
			)
			(layer "F.Fab")
		)
		(fp_line
			(start -0.12065 0.3048)
			(end -0.67945 0.3048)
			(stroke
				(width 0.1)
				(type default)
			)
			(layer "F.Fab")
		)
		(fp_line
			(start -0.67945 0.3048)
			(end -0.67945 -0.305054)
			(stroke
				(width 0.1)
				(type default)
			)
			(layer "F.Fab")
		)
		(pad "1" smd circle
			(at -0.40005 0 90)
			(size 0 0)
			(layers "F.Cu" "F.Mask" "F.Paste")
			(net "OCP_V3_2_P3V3_PWRGD")
		)
		(pad "2" smd circle
			(at 0.40005 0 90)
			(size 0 0)
			(layers "F.Cu" "F.Mask" "F.Paste")
			(net "HP_OCP_V3_2_RST_R")
		)
	)
	(footprint ""
		(layer "F.Cu")
		(at 27.58313 -174.11446)
		(property "Reference" "PR4699"
			(at 0 0 0)
			(layer "F.SilkS")
			(hide yes)
			(effects
				(font
					(size 1.27 1.27)
				)
			)
		)
		(property "Value" ""
			(at 0 0 0)
			(layer "F.Fab")
			(effects
				(font
					(size 1.27 1.27)
				)
			)
		)
		(duplicate_pad_numbers_are_jumpers no)
		(fp_line
			(start -0.7874 -0.4064)
			(end 0.7874 -0.4064)
			(stroke
				(width 0.1524)
				(type default)
			)
			(layer "F.SilkS")
		)
		(fp_line
			(start -0.7874 0.4064)
			(end -0.7874 -0.4064)
			(stroke
				(width 0.1524)
				(type default)
			)
			(layer "F.SilkS")
		)
		(fp_line
			(start 0.7874 -0.4064)
			(end 0.7874 0.4064)
			(stroke
				(width 0.1524)
				(type default)
			)
			(layer "F.SilkS")
		)
		(fp_line
			(start 0.7874 0.4064)
			(end -0.7874 0.4064)
			(stroke
				(width 0.1524)
				(type default)
			)
			(layer "F.SilkS")
		)
		(fp_line
			(start -0.67945 -0.305054)
			(end -0.12065 -0.305054)
			(stroke
				(width 0.1)
				(type default)
			)
			(layer "F.Fab")
		)
		(fp_line
			(start -0.67945 0.3048)
			(end -0.67945 -0.305054)
			(stroke
				(width 0.1)
				(type default)
			)
			(layer "F.Fab")
		)
		(fp_line
			(start -0.12065 -0.305054)
			(end -0.12065 -0.2794)
			(stroke
				(width 0.1)
				(type default)
			)
			(layer "F.Fab")
		)
		(fp_line
			(start -0.12065 -0.2794)
			(end 0.12065 -0.2794)
			(stroke
				(width 0.1)
				(type default)
			)
			(layer "F.Fab")
		)
		(fp_line
			(start -0.12065 0.2794)
			(end -0.12065 0.3048)
			(stroke
				(width 0.1)
				(type default)
			)
			(layer "F.Fab")
		)
		(fp_line
			(start -0.12065 0.3048)
			(end -0.67945 0.3048)
			(stroke
				(width 0.1)
				(type default)
			)
			(layer "F.Fab")
		)
		(fp_line
			(start 0.120396 0.2794)
			(end -0.12065 0.2794)
			(stroke
				(width 0.1)
				(type default)
			)
			(layer "F.Fab")
		)
		(fp_line
			(start 0.120396 0.3048)
			(end 0.120396 0.2794)
			(stroke
				(width 0.1)
				(type default)
			)
			(layer "F.Fab")
		)
		(fp_line
			(start 0.12065 -0.3048)
			(end 0.67945 -0.3048)
			(stroke
				(width 0.1)
				(type default)
			)
			(layer "F.Fab")
		)
		(fp_line
			(start 0.12065 -0.2794)
			(end 0.12065 -0.3048)
			(stroke
				(width 0.1)
				(type default)
			)
			(layer "F.Fab")
		)
		(fp_line
			(start 0.67945 -0.3048)
			(end 0.67945 0.3048)
			(stroke
				(width 0.1)
				(type default)
			)
			(layer "F.Fab")
		)
		(fp_line
			(start 0.67945 0.3048)
			(end 0.120396 0.3048)
			(stroke
				(width 0.1)
				(type default)
			)
			(layer "F.Fab")
		)
		(pad "1" smd circle
			(at -0.40005 0)
			(size 0 0)
			(layers "F.Cu" "F.Mask" "F.Paste")
			(net "PVNN_MAIN_CPU1_FB_RC")
		)
		(pad "2" smd circle
			(at 0.40005 0)
			(size 0 0)
			(layers "F.Cu" "F.Mask" "F.Paste")
			(net "PVNN_MAIN_CPU1")
		)
	)
	(footprint ""
		(layer "F.Cu")
		(at 179.12588 -126.964948 -90)
		(property "Reference" "R273"
			(at 0 0 270)
			(layer "F.SilkS")
			(hide yes)
			(effects
				(font
					(size 1.27 1.27)
				)
			)
		)
		(property "Value" ""
			(at 0 0 270)
			(layer "F.Fab")
			(effects
				(font
					(size 1.27 1.27)
				)
			)
		)
		(duplicate_pad_numbers_are_jumpers no)
		(fp_line
			(start -0.7874 0.4064)
			(end -0.7874 -0.4064)
			(stroke
				(width 0.1524)
				(type default)
			)
			(layer "F.SilkS")
		)
		(fp_line
			(start 0.7874 0.4064)
			(end -0.7874 0.4064)
			(stroke
				(width 0.1524)
				(type default)
			)
			(layer "F.SilkS")
		)
		(fp_line
			(start -0.7874 -0.4064)
			(end 0.7874 -0.4064)
			(stroke
				(width 0.1524)
				(type default)
			)
			(layer "F.SilkS")
		)
		(fp_line
			(start 0.7874 -0.4064)
			(end 0.7874 0.4064)
			(stroke
				(width 0.1524)
				(type default)
			)
			(layer "F.SilkS")
		)
		(fp_line
			(start -0.67945 0.3048)
			(end -0.67945 -0.305054)
			(stroke
				(width 0.1)
				(type default)
			)
			(layer "F.Fab")
		)
		(fp_line
			(start -0.12065 0.3048)
			(end -0.67945 0.3048)
			(stroke
				(width 0.1)
				(type default)
			)
			(layer "F.Fab")
		)
		(fp_line
			(start 0.120396 0.3048)
			(end 0.120396 0.2794)
			(stroke
				(width 0.1)
				(type default)
			)
			(layer "F.Fab")
		)
		(fp_line
			(start 0.67945 0.3048)
			(end 0.120396 0.3048)
			(stroke
				(width 0.1)
				(type default)
			)
			(layer "F.Fab")
		)
		(fp_line
			(start -0.12065 0.2794)
			(end -0.12065 0.3048)
			(stroke
				(width 0.1)
				(type default)
			)
			(layer "F.Fab")
		)
		(fp_line
			(start 0.120396 0.2794)
			(end -0.12065 0.2794)
			(stroke
				(width 0.1)
				(type default)
			)
			(layer "F.Fab")
		)
		(fp_line
			(start -0.12065 -0.2794)
			(end 0.12065 -0.2794)
			(stroke
				(width 0.1)
				(type default)
			)
			(layer "F.Fab")
		)
		(fp_line
			(start 0.12065 -0.2794)
			(end 0.12065 -0.3048)
			(stroke
				(width 0.1)
				(type default)
			)
			(layer "F.Fab")
		)
		(fp_line
			(start 0.12065 -0.3048)
			(end 0.67945 -0.3048)
			(stroke
				(width 0.1)
				(type default)
			)
			(layer "F.Fab")
		)
		(fp_line
			(start 0.67945 -0.3048)
			(end 0.67945 0.3048)
			(stroke
				(width 0.1)
				(type default)
			)
			(layer "F.Fab")
		)
		(fp_line
			(start -0.67945 -0.305054)
			(end -0.12065 -0.305054)
			(stroke
				(width 0.1)
				(type default)
			)
			(layer "F.Fab")
		)
		(fp_line
			(start -0.12065 -0.305054)
			(end -0.12065 -0.2794)
			(stroke
				(width 0.1)
				(type default)
			)
			(layer "F.Fab")
		)
		(pad "1" smd circle
			(at -0.40005 0 270)
			(size 0 0)
			(layers "F.Cu" "F.Mask" "F.Paste")
			(net "P3V3_AUX")
		)
		(pad "2" smd circle
			(at 0.40005 0 270)
			(size 0 0)
			(layers "F.Cu" "F.Mask" "F.Paste")
			(net "FM_CPU1_PROC_ID0")
		)
	)
)
